(kicad_pcb
	(version 20260206)
	(generator "pcbnew")
	(generator_version "10.0")
	(general
		(thickness 1.6)
		(legacy_teardrops no)
	)
	(paper "A4")
	(title_block
		(title "Wiwynn_Tioga_Pass_MB.brd")
		(comment 1 "Tioga Pass / footprints 1978-1985 of 4770")
	)
	(layers
		(0 "F.Cu" signal "TOP")
		(4 "In1.Cu" signal "L2GND")
		(6 "In2.Cu" signal "L3")
		(8 "In3.Cu" signal "L4GND")
		(10 "In4.Cu" signal "L5")
		(12 "In5.Cu" signal "L6GND")
		(14 "In6.Cu" signal "L7VCC")
		(16 "In7.Cu" signal "L8VCC")
		(18 "In8.Cu" signal "L9GND")
		(20 "In9.Cu" signal "L10")
		(22 "In10.Cu" signal "L11GND")
		(24 "In11.Cu" signal "L12")
		(26 "In12.Cu" signal "L13GND")
		(2 "B.Cu" signal "BOTTOM")
		(9 "F.Adhes" user "F.Adhesive")
		(11 "B.Adhes" user "B.Adhesive")
		(13 "F.Paste" user "Package Geometry/Pastemask Top")
		(15 "B.Paste" user "Package Geometry/Pastemask Bottom")
		(5 "F.SilkS" user "Ref Des/Silkscreen Top")
		(7 "B.SilkS" user "Ref Des/Silkscreen Bottom")
		(1 "F.Mask" user "Board Geometry/Soldermask Top")
		(3 "B.Mask" user "Board Geometry/Soldermask Bottom")
		(17 "Dwgs.User" user "User.Drawings")
		(19 "Cmts.User" user "User.Comments")
		(21 "Eco1.User" user "User.Eco1")
		(23 "Eco2.User" user "User.Eco2")
		(25 "Edge.Cuts" user "Board Geometry/Outline")
		(27 "Margin" user)
		(31 "F.CrtYd" user "Package Geometry/Place Bound Top")
		(29 "B.CrtYd" user "Package Geometry/Place Bound Bottom")
		(35 "F.Fab" user "Ref Des/Assembly Top")
		(33 "B.Fab" user "Ref Des/Assembly Bottom")
	)
	(footprint ""
		(layer "F.Cu")
		(at 38.9128 -50.5714)
		(property "Reference" "R1E5"
			(at 0 0 0)
			(layer "F.SilkS")
			(hide yes)
			(effects
				(font
					(size 1.27 1.27)
				)
			)
		)
		(property "Value" ""
			(at 0 0 0)
			(layer "F.Fab")
			(effects
				(font
					(size 1.27 1.27)
				)
			)
		)
		(duplicate_pad_numbers_are_jumpers no)
		(fp_poly
			(pts
				(xy -0.2794 -0.1016) (xy 0.2794 -0.1016) (xy 0.2794 0.9906) (xy -0.2794 0.9906)
			)
			(stroke
				(width 0)
				(type default)
			)
			(fill no)
			(layer "F.CrtYd")
		)
		(fp_line
			(start -0.2794 -0.1016)
			(end -0.2794 0.9906)
			(stroke
				(width 0.1)
				(type default)
			)
			(layer "F.Fab")
		)
		(fp_line
			(start -0.2794 0.9906)
			(end 0.2794 0.9906)
			(stroke
				(width 0.1)
				(type default)
			)
			(layer "F.Fab")
		)
		(fp_line
			(start 0.2794 -0.1016)
			(end -0.2794 -0.1016)
			(stroke
				(width 0.1)
				(type default)
			)
			(layer "F.Fab")
		)
		(fp_line
			(start 0.2794 0.9906)
			(end 0.2794 -0.1016)
			(stroke
				(width 0.1)
				(type default)
			)
			(layer "F.Fab")
		)
		(pad "1" smd rect
			(at 0 0)
			(size 0.508 0.508)
			(layers "F.Cu" "F.Mask" "F.Paste")
			(net "VSENSE_PVCCIN_CPU1_P")
		)
		(pad "2" smd rect
			(at 0 0.889)
			(size 0.508 0.508)
			(layers "F.Cu" "F.Mask" "F.Paste")
			(net "VSENSE_PVCCIN_CPU1_N")
		)
		(zone
			(layer "F.Cu")
			(hatch none 0.5)
			(connect_pads
				(clearance 0)
			)
			(min_thickness 0.25)
			(keepout
				(tracks allowed)
				(vias not_allowed)
				(pads allowed)
				(copperpour not_allowed)
				(footprints allowed)
			)
			(placement
				(enabled no)
				(sheetname "")
			)
			(fill
				(thermal_gap 0.5)
				(thermal_bridge_width 0.5)
				(island_removal_mode 0)
			)
			(polygon
				(pts
					(xy 38.6588 -50.3174) (xy 39.1668 -50.3174) (xy 39.1668 -49.9364) (xy 38.6588 -49.9364)
				)
			)
		)
		(zone
			(layer "F.Cu")
			(hatch none 0.5)
			(connect_pads
				(clearance 0)
			)
			(min_thickness 0.25)
			(keepout
				(tracks not_allowed)
				(vias allowed)
				(pads allowed)
				(copperpour not_allowed)
				(footprints allowed)
			)
			(placement
				(enabled no)
				(sheetname "")
			)
			(fill
				(thermal_gap 0.5)
				(thermal_bridge_width 0.5)
				(island_removal_mode 0)
			)
			(polygon
				(pts
					(xy 38.6588 -49.9364) (xy 39.1668 -49.9364) (xy 39.1668 -50.3174) (xy 38.6588 -50.3174)
				)
			)
		)
	)
	(footprint ""
		(layer "F.Cu")
		(at 265.684 -79.6036 180)
		(property "Reference" "C5D17"
			(at 0 0 180)
			(layer "F.SilkS")
			(hide yes)
			(effects
				(font
					(size 1.27 1.27)
				)
			)
		)
		(property "Value" ""
			(at 0 0 180)
			(layer "F.Fab")
			(effects
				(font
					(size 1.27 1.27)
				)
			)
		)
		(duplicate_pad_numbers_are_jumpers no)
		(fp_poly
			(pts
				(xy -0.4953 -0.2032) (xy 0.4953 -0.2032) (xy 0.4953 1.6002) (xy -0.4953 1.6002)
			)
			(stroke
				(width 0)
				(type default)
			)
			(fill no)
			(layer "F.CrtYd")
		)
		(fp_line
			(start 0.4953 1.6002)
			(end -0.4953 1.6002)
			(stroke
				(width 0.1)
				(type default)
			)
			(layer "F.Fab")
		)
		(fp_line
			(start 0.4953 -0.2032)
			(end 0.4953 1.6002)
			(stroke
				(width 0.1)
				(type default)
			)
			(layer "F.Fab")
		)
		(fp_line
			(start -0.4953 1.6002)
			(end -0.4953 -0.2032)
			(stroke
				(width 0.1)
				(type default)
			)
			(layer "F.Fab")
		)
		(fp_line
			(start -0.4953 -0.2032)
			(end 0.4953 -0.2032)
			(stroke
				(width 0.1)
				(type default)
			)
			(layer "F.Fab")
		)
		(pad "1" smd rect
			(at 0 0 180)
			(size 0.762 0.889)
			(layers "F.Cu" "F.Mask" "F.Paste")
			(net "PVCCIN_CPU0")
		)
		(pad "2" smd rect
			(at 0 1.397 180)
			(size 0.762 0.889)
			(layers "F.Cu" "F.Mask" "F.Paste")
			(net "GND")
		)
		(zone
			(layer "F.Cu")
			(hatch none 0.5)
			(connect_pads
				(clearance 0)
			)
			(min_thickness 0.25)
			(keepout
				(tracks not_allowed)
				(vias allowed)
				(pads allowed)
				(copperpour not_allowed)
				(footprints allowed)
			)
			(placement
				(enabled no)
				(sheetname "")
			)
			(fill
				(thermal_gap 0.5)
				(thermal_bridge_width 0.5)
				(island_removal_mode 0)
			)
			(polygon
				(pts
					(xy 266.065 -80.0481) (xy 265.303 -80.0481) (xy 265.303 -80.5561) (xy 266.065 -80.5561)
				)
			)
		)
	)
	(footprint ""
		(layer "F.Cu")
		(at 409.3972 -116.6114 90)
		(property "Reference" "R8B20"
			(at 0 0 90)
			(layer "F.SilkS")
			(hide yes)
			(effects
				(font
					(size 1.27 1.27)
				)
			)
		)
		(property "Value" ""
			(at 0 0 90)
			(layer "F.Fab")
			(effects
				(font
					(size 1.27 1.27)
				)
			)
		)
		(duplicate_pad_numbers_are_jumpers no)
		(fp_poly
			(pts
				(xy -0.2794 -0.1016) (xy 0.2794 -0.1016) (xy 0.2794 0.9906) (xy -0.2794 0.9906)
			)
			(stroke
				(width 0)
				(type default)
			)
			(fill no)
			(layer "F.CrtYd")
		)
		(fp_line
			(start 0.2794 -0.1016)
			(end -0.2794 -0.1016)
			(stroke
				(width 0.1)
				(type default)
			)
			(layer "F.Fab")
		)
		(fp_line
			(start -0.2794 -0.1016)
			(end -0.2794 0.9906)
			(stroke
				(width 0.1)
				(type default)
			)
			(layer "F.Fab")
		)
		(fp_line
			(start 0.2794 0.9906)
			(end 0.2794 -0.1016)
			(stroke
				(width 0.1)
				(type default)
			)
			(layer "F.Fab")
		)
		(fp_line
			(start -0.2794 0.9906)
			(end 0.2794 0.9906)
			(stroke
				(width 0.1)
				(type default)
			)
			(layer "F.Fab")
		)
		(pad "1" smd rect
			(at 0 0 90)
			(size 0.508 0.508)
			(layers "F.Cu" "F.Mask" "F.Paste")
			(net "H_PMSYNC_CLK_24M_R")
		)
		(pad "2" smd rect
			(at 0 0.889 90)
			(size 0.508 0.508)
			(layers "F.Cu" "F.Mask" "F.Paste")
			(net "H_PMSYNC_CLK_24M")
		)
		(zone
			(layer "F.Cu")
			(hatch none 0.5)
			(connect_pads
				(clearance 0)
			)
			(min_thickness 0.25)
			(keepout
				(tracks allowed)
				(vias not_allowed)
				(pads allowed)
				(copperpour not_allowed)
				(footprints allowed)
			)
			(placement
				(enabled no)
				(sheetname "")
			)
			(fill
				(thermal_gap 0.5)
				(thermal_bridge_width 0.5)
				(island_removal_mode 0)
			)
			(polygon
				(pts
					(xy 409.6512 -116.3574) (xy 409.6512 -116.8654) (xy 410.0322 -116.8654) (xy 410.0322 -116.3574)
				)
			)
		)
		(zone
			(layer "F.Cu")
			(hatch none 0.5)
			(connect_pads
				(clearance 0)
			)
			(min_thickness 0.25)
			(keepout
				(tracks not_allowed)
				(vias allowed)
				(pads allowed)
				(copperpour not_allowed)
				(footprints allowed)
			)
			(placement
				(enabled no)
				(sheetname "")
			)
			(fill
				(thermal_gap 0.5)
				(thermal_bridge_width 0.5)
				(island_removal_mode 0)
			)
			(polygon
				(pts
					(xy 410.0322 -116.3574) (xy 410.0322 -116.8654) (xy 409.6512 -116.8654) (xy 409.6512 -116.3574)
				)
			)
		)
	)
	(footprint ""
		(layer "F.Cu")
		(at 367.116106 -64.81064 90)
		(property "Reference" "R7E5"
			(at 0 0 90)
			(layer "F.SilkS")
			(hide yes)
			(effects
				(font
					(size 1.27 1.27)
				)
			)
		)
		(property "Value" ""
			(at 0 0 90)
			(layer "F.Fab")
			(effects
				(font
					(size 1.27 1.27)
				)
			)
		)
		(duplicate_pad_numbers_are_jumpers no)
		(fp_poly
			(pts
				(xy -0.2794 -0.1016) (xy 0.2794 -0.1016) (xy 0.2794 0.9906) (xy -0.2794 0.9906)
			)
			(stroke
				(width 0)
				(type default)
			)
			(fill no)
			(layer "F.CrtYd")
		)
		(fp_line
			(start 0.2794 -0.1016)
			(end -0.2794 -0.1016)
			(stroke
				(width 0.1)
				(type default)
			)
			(layer "F.Fab")
		)
		(fp_line
			(start -0.2794 -0.1016)
			(end -0.2794 0.9906)
			(stroke
				(width 0.1)
				(type default)
			)
			(layer "F.Fab")
		)
		(fp_line
			(start 0.2794 0.9906)
			(end 0.2794 -0.1016)
			(stroke
				(width 0.1)
				(type default)
			)
			(layer "F.Fab")
		)
		(fp_line
			(start -0.2794 0.9906)
			(end 0.2794 0.9906)
			(stroke
				(width 0.1)
				(type default)
			)
			(layer "F.Fab")
		)
		(pad "1" smd rect
			(at 0 0 90)
			(size 0.508 0.508)
			(layers "F.Cu" "F.Mask" "F.Paste")
			(net "P3V3_STBY")
		)
		(pad "2" smd rect
			(at 0 0.889 90)
			(size 0.508 0.508)
			(layers "F.Cu" "F.Mask" "F.Paste")
			(net "PU_THERMTRIP_FORCE_N")
		)
		(zone
			(layer "F.Cu")
			(hatch none 0.5)
			(connect_pads
				(clearance 0)
			)
			(min_thickness 0.25)
			(keepout
				(tracks allowed)
				(vias not_allowed)
				(pads allowed)
				(copperpour not_allowed)
				(footprints allowed)
			)
			(placement
				(enabled no)
				(sheetname "")
			)
			(fill
				(thermal_gap 0.5)
				(thermal_bridge_width 0.5)
				(island_removal_mode 0)
			)
			(polygon
				(pts
					(xy 367.370106 -64.55664) (xy 367.370106 -65.06464) (xy 367.751106 -65.06464) (xy 367.751106 -64.55664)
				)
			)
		)
		(zone
			(layer "F.Cu")
			(hatch none 0.5)
			(connect_pads
				(clearance 0)
			)
			(min_thickness 0.25)
			(keepout
				(tracks not_allowed)
				(vias allowed)
				(pads allowed)
				(copperpour not_allowed)
				(footprints allowed)
			)
			(placement
				(enabled no)
				(sheetname "")
			)
			(fill
				(thermal_gap 0.5)
				(thermal_bridge_width 0.5)
				(island_removal_mode 0)
			)
			(polygon
				(pts
					(xy 367.751106 -64.55664) (xy 367.751106 -65.06464) (xy 367.370106 -65.06464) (xy 367.370106 -64.55664)
				)
			)
		)
	)
	(footprint ""
		(layer "F.Cu")
		(at 417.9316 -57.1119 180)
		(property "Reference" "R8E14"
			(at 0 0 180)
			(layer "F.SilkS")
			(hide yes)
			(effects
				(font
					(size 1.27 1.27)
				)
			)
		)
		(property "Value" ""
			(at 0 0 180)
			(layer "F.Fab")
			(effects
				(font
					(size 1.27 1.27)
				)
			)
		)
		(duplicate_pad_numbers_are_jumpers no)
		(fp_poly
			(pts
				(xy -0.2794 -0.1016) (xy 0.2794 -0.1016) (xy 0.2794 0.9906) (xy -0.2794 0.9906)
			)
			(stroke
				(width 0)
				(type default)
			)
			(fill no)
			(layer "F.CrtYd")
		)
		(fp_line
			(start 0.2794 0.9906)
			(end 0.2794 -0.1016)
			(stroke
				(width 0.1)
				(type default)
			)
			(layer "F.Fab")
		)
		(fp_line
			(start 0.2794 -0.1016)
			(end -0.2794 -0.1016)
			(stroke
				(width 0.1)
				(type default)
			)
			(layer "F.Fab")
		)
		(fp_line
			(start -0.2794 0.9906)
			(end 0.2794 0.9906)
			(stroke
				(width 0.1)
				(type default)
			)
			(layer "F.Fab")
		)
		(fp_line
			(start -0.2794 -0.1016)
			(end -0.2794 0.9906)
			(stroke
				(width 0.1)
				(type default)
			)
			(layer "F.Fab")
		)
		(pad "1" smd rect
			(at 0 0 180)
			(size 0.508 0.508)
			(layers "F.Cu" "F.Mask" "F.Paste")
			(net "P3V3_STBY")
		)
		(pad "2" smd rect
			(at 0 0.889 180)
			(size 0.508 0.508)
			(layers "F.Cu" "F.Mask" "F.Paste")
			(net "RST_PLTRST_TOP_SWAP")
		)
		(zone
			(layer "F.Cu")
			(hatch none 0.5)
			(connect_pads
				(clearance 0)
			)
			(min_thickness 0.25)
			(keepout
				(tracks not_allowed)
				(vias allowed)
				(pads allowed)
				(copperpour not_allowed)
				(footprints allowed)
			)
			(placement
				(enabled no)
				(sheetname "")
			)
			(fill
				(thermal_gap 0.5)
				(thermal_bridge_width 0.5)
				(island_removal_mode 0)
			)
			(polygon
				(pts
					(xy 418.1856 -57.7469) (xy 417.6776 -57.7469) (xy 417.6776 -57.3659) (xy 418.1856 -57.3659)
				)
			)
		)
		(zone
			(layer "F.Cu")
			(hatch none 0.5)
			(connect_pads
				(clearance 0)
			)
			(min_thickness 0.25)
			(keepout
				(tracks allowed)
				(vias not_allowed)
				(pads allowed)
				(copperpour not_allowed)
				(footprints allowed)
			)
			(placement
				(enabled no)
				(sheetname "")
			)
			(fill
				(thermal_gap 0.5)
				(thermal_bridge_width 0.5)
				(island_removal_mode 0)
			)
			(polygon
				(pts
					(xy 418.1856 -57.3659) (xy 417.6776 -57.3659) (xy 417.6776 -57.7469) (xy 418.1856 -57.7469)
				)
			)
		)
	)
	(footprint ""
		(layer "F.Cu")
		(at 368.184938 -102.30739 -90)
		(property "Reference" "C7C9"
			(at 0 0 270)
			(layer "F.SilkS")
			(hide yes)
			(effects
				(font
					(size 1.27 1.27)
				)
			)
		)
		(property "Value" ""
			(at 0 0 270)
			(layer "F.Fab")
			(effects
				(font
					(size 1.27 1.27)
				)
			)
		)
		(duplicate_pad_numbers_are_jumpers no)
		(fp_poly
			(pts
				(xy -0.4953 -0.2032) (xy 0.4953 -0.2032) (xy 0.4953 1.6002) (xy -0.4953 1.6002)
			)
			(stroke
				(width 0)
				(type default)
			)
			(fill no)
			(layer "F.CrtYd")
		)
		(fp_line
			(start -0.4953 1.6002)
			(end -0.4953 -0.2032)
			(stroke
				(width 0.1)
				(type default)
			)
			(layer "F.Fab")
		)
		(fp_line
			(start 0.4953 1.6002)
			(end -0.4953 1.6002)
			(stroke
				(width 0.1)
				(type default)
			)
			(layer "F.Fab")
		)
		(fp_line
			(start -0.4953 -0.2032)
			(end 0.4953 -0.2032)
			(stroke
				(width 0.1)
				(type default)
			)
			(layer "F.Fab")
		)
		(fp_line
			(start 0.4953 -0.2032)
			(end 0.4953 1.6002)
			(stroke
				(width 0.1)
				(type default)
			)
			(layer "F.Fab")
		)
		(pad "1" smd rect
			(at 0 0 270)
			(size 0.762 0.889)
			(layers "F.Cu" "F.Mask" "F.Paste")
			(net "PVNN_PCH_STBY")
		)
		(pad "2" smd rect
			(at 0 1.397 270)
			(size 0.762 0.889)
			(layers "F.Cu" "F.Mask" "F.Paste")
			(net "GND")
		)
		(zone
			(layer "F.Cu")
			(hatch none 0.5)
			(connect_pads
				(clearance 0)
			)
			(min_thickness 0.25)
			(keepout
				(tracks not_allowed)
				(vias allowed)
				(pads allowed)
				(copperpour not_allowed)
				(footprints allowed)
			)
			(placement
				(enabled no)
				(sheetname "")
			)
			(fill
				(thermal_gap 0.5)
				(thermal_bridge_width 0.5)
				(island_removal_mode 0)
			)
			(polygon
				(pts
					(xy 367.740438 -102.68839) (xy 367.740438 -101.92639) (xy 367.232438 -101.92639) (xy 367.232438 -102.68839)
				)
			)
		)
	)
	(footprint ""
		(layer "F.Cu")
		(at 155.194 -27.9908 -90)
		(property "Reference" "R3F6"
			(at 0 0 270)
			(layer "F.SilkS")
			(hide yes)
			(effects
				(font
					(size 1.27 1.27)
				)
			)
		)
		(property "Value" ""
			(at 0 0 270)
			(layer "F.Fab")
			(effects
				(font
					(size 1.27 1.27)
				)
			)
		)
		(duplicate_pad_numbers_are_jumpers no)
		(fp_poly
			(pts
				(xy -0.2794 -0.1016) (xy 0.2794 -0.1016) (xy 0.2794 0.9906) (xy -0.2794 0.9906)
			)
			(stroke
				(width 0)
				(type default)
			)
			(fill no)
			(layer "F.CrtYd")
		)
		(fp_line
			(start -0.2794 0.9906)
			(end 0.2794 0.9906)
			(stroke
				(width 0.1)
				(type default)
			)
			(layer "F.Fab")
		)
		(fp_line
			(start 0.2794 0.9906)
			(end 0.2794 -0.1016)
			(stroke
				(width 0.1)
				(type default)
			)
			(layer "F.Fab")
		)
		(fp_line
			(start -0.2794 -0.1016)
			(end -0.2794 0.9906)
			(stroke
				(width 0.1)
				(type default)
			)
			(layer "F.Fab")
		)
		(fp_line
			(start 0.2794 -0.1016)
			(end -0.2794 -0.1016)
			(stroke
				(width 0.1)
				(type default)
			)
			(layer "F.Fab")
		)
		(pad "1" smd rect
			(at 0 0 270)
			(size 0.508 0.508)
			(layers "F.Cu" "F.Mask" "F.Paste")
			(net "CLK_322M_156M_CPU1_OSC_VRM_DP")
		)
		(pad "2" smd rect
			(at 0 0.889 270)
			(size 0.508 0.508)
			(layers "F.Cu" "F.Mask" "F.Paste")
			(net "CLK_322M_OSC_CPU1_RC_DP")
		)
		(zone
			(layer "F.Cu")
			(hatch none 0.5)
			(connect_pads
				(clearance 0)
			)
			(min_thickness 0.25)
			(keepout
				(tracks not_allowed)
				(vias allowed)
				(pads allowed)
				(copperpour not_allowed)
				(footprints allowed)
			)
			(placement
				(enabled no)
				(sheetname "")
			)
			(fill
				(thermal_gap 0.5)
				(thermal_bridge_width 0.5)
				(island_removal_mode 0)
			)
			(polygon
				(pts
					(xy 154.559 -28.2448) (xy 154.559 -27.7368) (xy 154.94 -27.7368) (xy 154.94 -28.2448)
				)
			)
		)
		(zone
			(layer "F.Cu")
			(hatch none 0.5)
			(connect_pads
				(clearance 0)
			)
			(min_thickness 0.25)
			(keepout
				(tracks allowed)
				(vias not_allowed)
				(pads allowed)
				(copperpour not_allowed)
				(footprints allowed)
			)
			(placement
				(enabled no)
				(sheetname "")
			)
			(fill
				(thermal_gap 0.5)
				(thermal_bridge_width 0.5)
				(island_removal_mode 0)
			)
			(polygon
				(pts
					(xy 154.94 -28.2448) (xy 154.94 -27.7368) (xy 154.559 -27.7368) (xy 154.559 -28.2448)
				)
			)
		)
	)
	(footprint ""
		(layer "F.Cu")
		(at 275.48332 -83.88604)
		(property "Reference" "R5D1"
			(at 0 0 0)
			(layer "F.SilkS")
			(hide yes)
			(effects
				(font
					(size 1.27 1.27)
				)
			)
		)
		(property "Value" ""
			(at 0 0 0)
			(layer "F.Fab")
			(effects
				(font
					(size 1.27 1.27)
				)
			)
		)
		(duplicate_pad_numbers_are_jumpers no)
		(fp_poly
			(pts
				(xy -0.2794 -0.1016) (xy 0.2794 -0.1016) (xy 0.2794 0.9906) (xy -0.2794 0.9906)
			)
			(stroke
				(width 0)
				(type default)
			)
			(fill no)
			(layer "F.CrtYd")
		)
		(fp_line
			(start -0.2794 -0.1016)
			(end -0.2794 0.9906)
			(stroke
				(width 0.1)
				(type default)
			)
			(layer "F.Fab")
		)
		(fp_line
			(start -0.2794 0.9906)
			(end 0.2794 0.9906)
			(stroke
				(width 0.1)
				(type default)
			)
			(layer "F.Fab")
		)
		(fp_line
			(start 0.2794 -0.1016)
			(end -0.2794 -0.1016)
			(stroke
				(width 0.1)
				(type default)
			)
			(layer "F.Fab")
		)
		(fp_line
			(start 0.2794 0.9906)
			(end 0.2794 -0.1016)
			(stroke
				(width 0.1)
				(type default)
			)
			(layer "F.Fab")
		)
		(pad "1" smd rect
			(at 0 0)
			(size 0.508 0.508)
			(layers "F.Cu" "F.Mask" "F.Paste")
			(net "A_CPU0_DEF_RCOMP0")
		)
		(pad "2" smd rect
			(at 0 0.889)
			(size 0.508 0.508)
			(layers "F.Cu" "F.Mask" "F.Paste")
			(net "GND")
		)
		(zone
			(layer "F.Cu")
			(hatch none 0.5)
			(connect_pads
				(clearance 0)
			)
			(min_thickness 0.25)
			(keepout
				(tracks allowed)
				(vias not_allowed)
				(pads allowed)
				(copperpour not_allowed)
				(footprints allowed)
			)
			(placement
				(enabled no)
				(sheetname "")
			)
			(fill
				(thermal_gap 0.5)
				(thermal_bridge_width 0.5)
				(island_removal_mode 0)
			)
			(polygon
				(pts
					(xy 275.22932 -83.63204) (xy 275.73732 -83.63204) (xy 275.73732 -83.25104) (xy 275.22932 -83.25104)
				)
			)
		)
		(zone
			(layer "F.Cu")
			(hatch none 0.5)
			(connect_pads
				(clearance 0)
			)
			(min_thickness 0.25)
			(keepout
				(tracks not_allowed)
				(vias allowed)
				(pads allowed)
				(copperpour not_allowed)
				(footprints allowed)
			)
			(placement
				(enabled no)
				(sheetname "")
			)
			(fill
				(thermal_gap 0.5)
				(thermal_bridge_width 0.5)
				(island_removal_mode 0)
			)
			(polygon
				(pts
					(xy 275.22932 -83.25104) (xy 275.73732 -83.25104) (xy 275.73732 -83.63204) (xy 275.22932 -83.63204)
				)
			)
		)
	)
)
